(kicad_pcb
	(version 20241229)
	(generator "pcbnew")
	(generator_version "9.0")
	(general
		(thickness 1.63)
		(legacy_teardrops no)
	)
	(paper "A4")
	(title_block
		(title "CM4 Baseboard")
		(date "2026-01-05")
		(rev "1.1.1")
		(company "Antmicro Ltd")
		(comment 1 "www.antmicro.com")
		(comment 9 "footprints 37-40 of 506")
	)
	(layers
		(0 "F.Cu" signal)
		(4 "In1.Cu" power)
		(6 "In2.Cu" power)
		(8 "In3.Cu" signal)
		(10 "In4.Cu" signal)
		(2 "B.Cu" signal)
		(9 "F.Adhes" user "F.Adhesive")
		(11 "B.Adhes" user "B.Adhesive")
		(13 "F.Paste" user)
		(15 "B.Paste" user)
		(5 "F.SilkS" user "F.Silkscreen")
		(7 "B.SilkS" user "B.Silkscreen")
		(1 "F.Mask" user)
		(3 "B.Mask" user)
		(17 "Dwgs.User" user "User.Drawings")
		(19 "Cmts.User" user "User.Comments")
		(21 "Eco1.User" user "User.Eco1")
		(23 "Eco2.User" user "User.Eco2")
		(25 "Edge.Cuts" user)
		(27 "Margin" user)
		(31 "F.CrtYd" user "F.Courtyard")
		(29 "B.CrtYd" user "B.Courtyard")
		(35 "F.Fab" user)
		(33 "B.Fab" user)
	)
	(footprint "antmicro-footprints:SOT-23-3"
		(layer "F.Cu")
		(at 107.467962 148.467)
		(property "Reference" "Q203"
			(at -1.8 -1.8 0)
			(layer "F.SilkS")
			(effects
				(font
					(size 0.7 0.7)
					(thickness 0.15)
				)
				(justify left bottom)
			)
		)
		(property "Value" "SSM3J332R"
			(at -1.9 2.7 0)
			(layer "F.Fab")
			(effects
				(font
					(size 0.7 0.7)
					(thickness 0.15)
				)
				(justify left bottom)
			)
		)
		(property "Datasheet" "https://www.mouser.com/datasheet/2/408/SSM3J332R_datasheet_en_20181015-1150575.pdf"
			(at 0 0 0)
			(layer "F.Fab")
			(hide yes)
			(effects
				(font
					(size 1.27 1.27)
					(thickness 0.15)
				)
			)
		)
		(property "MPN" "SSM3J332R,LF"
			(at 0 0 0)
			(unlocked yes)
			(layer "F.Fab")
			(hide yes)
			(effects
				(font
					(size 1 1)
					(thickness 0.15)
				)
			)
		)
		(property "Manufacturer" "Toshiba"
			(at 0 0 0)
			(unlocked yes)
			(layer "F.Fab")
			(hide yes)
			(effects
				(font
					(size 1 1)
					(thickness 0.15)
				)
			)
		)
		(property "Author" "Antmicro"
			(at 0 0 0)
			(unlocked yes)
			(layer "F.Fab")
			(hide yes)
			(effects
				(font
					(size 1 1)
					(thickness 0.15)
				)
			)
		)
		(property "License" "Apache-2.0"
			(at 0 0 0)
			(unlocked yes)
			(layer "F.Fab")
			(hide yes)
			(effects
				(font
					(size 1 1)
					(thickness 0.15)
				)
			)
		)
		(sheetname "/Compute module/")
		(sheetfile "compute-module.kicad_sch")
		(attr smd)
		(fp_line
			(start -1.45 -1.35)
			(end -0.85 -1.35)
			(stroke
				(width 0.15)
				(type solid)
			)
			(layer "F.SilkS")
		)
		(fp_line
			(start -0.85 -1.35)
			(end -0.7 -1.5)
			(stroke
				(width 0.15)
				(type solid)
			)
			(layer "F.SilkS")
		)
		(fp_line
			(start -0.7 1.5)
			(end -0.7 1.35)
			(stroke
				(width 0.15)
				(type solid)
			)
			(layer "F.SilkS")
		)
		(fp_line
			(start 0.7 -1.5)
			(end -0.7 -1.5)
			(stroke
				(width 0.15)
				(type solid)
			)
			(layer "F.SilkS")
		)
		(fp_line
			(start 0.7 -0.4)
			(end 0.7 -1.5)
			(stroke
				(width 0.15)
				(type solid)
			)
			(layer "F.SilkS")
		)
		(fp_line
			(start 0.7 0.4)
			(end 0.7 1.5)
			(stroke
				(width 0.15)
				(type solid)
			)
			(layer "F.SilkS")
		)
		(fp_line
			(start 0.7 1.5)
			(end -0.7 1.5)
			(stroke
				(width 0.15)
				(type solid)
			)
			(layer "F.SilkS")
		)
		(fp_line
			(start -1.75 -0.5)
			(end -1.75 -1.4)
			(stroke
				(width 0.05)
				(type solid)
			)
			(layer "F.CrtYd")
		)
		(fp_line
			(start -1.75 0.5)
			(end -0.85 0.5)
			(stroke
				(width 0.05)
				(type solid)
			)
			(layer "F.CrtYd")
		)
		(fp_line
			(start -1.75 1.4)
			(end -1.75 0.5)
			(stroke
				(width 0.05)
				(type solid)
			)
			(layer "F.CrtYd")
		)
		(fp_line
			(start -0.9 -1.6)
			(end -0.9 -1.4)
			(stroke
				(width 0.05)
				(type solid)
			)
			(layer "F.CrtYd")
		)
		(fp_line
			(start -0.9 -1.6)
			(end 0.825 -1.6)
			(stroke
				(width 0.05)
				(type solid)
			)
			(layer "F.CrtYd")
		)
		(fp_line
			(start -0.9 -1.4)
			(end -1.75 -1.4)
			(stroke
				(width 0.05)
				(type solid)
			)
			(layer "F.CrtYd")
		)
		(fp_line
			(start -0.85 -0.5)
			(end -1.75 -0.5)
			(stroke
				(width 0.05)
				(type solid)
			)
			(layer "F.CrtYd")
		)
		(fp_line
			(start -0.85 0.5)
			(end -0.85 -0.5)
			(stroke
				(width 0.05)
				(type solid)
			)
			(layer "F.CrtYd")
		)
		(fp_line
			(start -0.85 1.4)
			(end -1.75 1.4)
			(stroke
				(width 0.05)
				(type solid)
			)
			(layer "F.CrtYd")
		)
		(fp_line
			(start -0.85 1.65)
			(end -0.85 1.4)
			(stroke
				(width 0.05)
				(type solid)
			)
			(layer "F.CrtYd")
		)
		(fp_line
			(start 0.825 -1.6)
			(end 0.825 -0.45)
			(stroke
				(width 0.05)
				(type solid)
			)
			(layer "F.CrtYd")
		)
		(fp_line
			(start 0.825 -0.45)
			(end 1.75 -0.45)
			(stroke
				(width 0.05)
				(type solid)
			)
			(layer "F.CrtYd")
		)
		(fp_line
			(start 0.85 0.45)
			(end 0.85 1.65)
			(stroke
				(width 0.05)
				(type solid)
			)
			(layer "F.CrtYd")
		)
		(fp_line
			(start 0.85 1.65)
			(end -0.85 1.65)
			(stroke
				(width 0.05)
				(type solid)
			)
			(layer "F.CrtYd")
		)
		(fp_line
			(start 1.75 -0.45)
			(end 1.75 0.45)
			(stroke
				(width 0.05)
				(type solid)
			)
			(layer "F.CrtYd")
		)
		(fp_line
			(start 1.75 0.45)
			(end 0.85 0.45)
			(stroke
				(width 0.05)
				(type solid)
			)
			(layer "F.CrtYd")
		)
		(fp_line
			(start -0.712 -1.325)
			(end -0.712 1.523)
			(stroke
				(width 0.15)
				(type solid)
			)
			(layer "F.Fab")
		)
		(fp_line
			(start -0.712 1.519)
			(end 0.688 1.519)
			(stroke
				(width 0.15)
				(type solid)
			)
			(layer "F.Fab")
		)
		(fp_line
			(start -0.437 -1.526)
			(end -0.712 -1.325)
			(stroke
				(width 0.15)
				(type solid)
			)
			(layer "F.Fab")
		)
		(fp_line
			(start -0.437 -1.526)
			(end 0.688 -1.526)
			(stroke
				(width 0.15)
				(type solid)
			)
			(layer "F.Fab")
		)
		(fp_line
			(start 0.688 1.519)
			(end 0.688 -1.52)
			(stroke
				(width 0.15)
				(type solid)
			)
			(layer "F.Fab")
		)
		(fp_text user "${REFERENCE}"
			(at -1.837 4 0)
			(layer "F.Fab")
			(effects
				(font
					(size 0.7 0.7)
					(thickness 0.15)
				)
				(justify left bottom)
			)
		)
		(fp_text user "License: Apache-2.0"
			(at -1.8 6.8 0)
			(layer "F.Fab")
			(effects
				(font
					(size 0.7 0.7)
					(thickness 0.15)
				)
				(justify left bottom)
			)
		)
		(fp_text user "Author: Antmicro"
			(at -1.837 5.3 0)
			(layer "F.Fab")
			(effects
				(font
					(size 0.7 0.7)
					(thickness 0.15)
				)
				(justify left bottom)
			)
		)
		(pad "1" smd roundrect
			(at -1.1 -0.951)
			(size 1 0.6)
			(layers "F.Cu" "F.Mask" "F.Paste")
			(roundrect_rratio 0.15)
			(net 327 "Net-(Q201-D)")
			(pinfunction "G")
			(pintype "input")
		)
		(pad "2" smd roundrect
			(at -1.1 0.949)
			(size 1 0.6)
			(layers "F.Cu" "F.Mask" "F.Paste")
			(roundrect_rratio 0.15)
			(net 10 "+5V")
			(pinfunction "S")
			(pintype "passive")
		)
		(pad "3" smd roundrect
			(at 1.1 -0.0005)
			(size 1 0.6)
			(layers "F.Cu" "F.Mask" "F.Paste")
			(roundrect_rratio 0.15)
			(net 258 "/Compute module/Pf_5V.SDA")
			(pinfunction "D")
			(pintype "passive")
		)
	)
	(footprint "antmicro-footprints:C_0402_1005Metric"
		(layer "F.Cu")
		(at 66.092962 175.7005 -90)
		(descr "Capacitor SMD 0402")
		(tags "capacitor SMD 0402")
		(property "Reference" "C817"
			(at -3.504 13.925 90)
			(layer "F.SilkS")
			(effects
				(font
					(size 0.7 0.7)
					(thickness 0.15)
				)
				(justify right bottom)
			)
		)
		(property "Value" "C_template_name_0402"
			(at -1.022927 2.155213 90)
			(layer "F.Fab")
			(effects
				(font
					(size 0.7 0.7)
					(thickness 0.15)
				)
				(justify right bottom)
			)
		)
		(property "Datasheet" "template_datasheet"
			(at 0 0 270)
			(layer "F.Fab")
			(hide yes)
			(effects
				(font
					(size 1.27 1.27)
					(thickness 0.15)
				)
			)
		)
		(property "MPN" "template_MPN"
			(at 0 0 270)
			(unlocked yes)
			(layer "F.Fab")
			(hide yes)
			(effects
				(font
					(size 1 1)
					(thickness 0.15)
				)
			)
		)
		(property "Manufacturer" "template_manufacturer"
			(at 0 0 270)
			(unlocked yes)
			(layer "F.Fab")
			(hide yes)
			(effects
				(font
					(size 1 1)
					(thickness 0.15)
				)
			)
		)
		(property "License" "Apache-2.0"
			(at 0 0 270)
			(unlocked yes)
			(layer "F.Fab")
			(hide yes)
			(effects
				(font
					(size 1 1)
					(thickness 0.15)
				)
			)
		)
		(property "Author" "Antmicro"
			(at 0 0 270)
			(unlocked yes)
			(layer "F.Fab")
			(hide yes)
			(effects
				(font
					(size 1 1)
					(thickness 0.15)
				)
			)
		)
		(property "Val" "template_value"
			(at 0 0 270)
			(unlocked yes)
			(layer "F.Fab")
			(hide yes)
			(effects
				(font
					(size 1 1)
					(thickness 0.15)
				)
			)
		)
		(property "Voltage" "template_voltage"
			(at 0 0 270)
			(unlocked yes)
			(layer "F.Fab")
			(hide yes)
			(effects
				(font
					(size 1 1)
					(thickness 0.15)
				)
			)
		)
		(property "Dielectric" "template_dielectric"
			(at 0 0 270)
			(unlocked yes)
			(layer "F.Fab")
			(hide yes)
			(effects
				(font
					(size 1 1)
					(thickness 0.15)
				)
			)
		)
		(sheetname "/Peripherals/")
		(sheetfile "peripherals.kicad_sch")
		(attr smd exclude_from_pos_files exclude_from_bom dnp)
		(fp_rect
			(start -0.925 -0.47)
			(end 0.925 0.47)
			(stroke
				(width 0.05)
				(type default)
			)
			(fill no)
			(layer "F.CrtYd")
		)
		(fp_line
			(start -0.494 0.248)
			(end -0.494 -0.25)
			(stroke
				(width 0.15)
				(type solid)
			)
			(layer "F.Fab")
		)
		(fp_line
			(start 0.504 0.248)
			(end -0.494 0.248)
			(stroke
				(width 0.15)
				(type solid)
			)
			(layer "F.Fab")
		)
		(fp_line
			(start -0.494 -0.25)
			(end 0.504 -0.25)
			(stroke
				(width 0.15)
				(type solid)
			)
			(layer "F.Fab")
		)
		(fp_line
			(start 0.504 -0.25)
			(end 0.504 0.248)
			(stroke
				(width 0.15)
				(type solid)
			)
			(layer "F.Fab")
		)
		(fp_text user "${REFERENCE}"
			(at -0.939 4.599 270)
			(layer "F.Fab")
			(effects
				(font
					(size 0.7 0.7)
					(thickness 0.15)
				)
				(justify left bottom)
			)
		)
		(fp_text user "License: Apache-2.0"
			(at -0.939 5.799 270)
			(layer "F.Fab")
			(effects
				(font
					(size 0.7 0.7)
					(thickness 0.15)
				)
				(justify left bottom)
			)
		)
		(fp_text user "Author: Antmicro"
			(at -0.939 3.399 270)
			(layer "F.Fab")
			(effects
				(font
					(size 0.7 0.7)
					(thickness 0.15)
				)
				(justify left bottom)
			)
		)
		(pad "1" smd roundrect
			(at -0.48 0 270)
			(size 0.59 0.64)
			(layers "F.Cu" "F.Mask" "F.Paste")
			(roundrect_rratio 0.25)
			(net 110 "Net-(C817-Pad1)")
			(pintype "passive")
		)
		(pad "2" smd roundrect
			(at 0.48 0 270)
			(size 0.59 0.64)
			(layers "F.Cu" "F.Mask" "F.Paste")
			(roundrect_rratio 0.25)
			(net 3 "GND")
			(pintype "passive")
		)
	)
	(footprint "antmicro-footprints:LED_0603_1608Metric_G"
		(layer "F.Cu")
		(at 76.517962 173.2065 180)
		(descr "LED SMD 0603 Green")
		(tags "LED SMD 0603 Green")
		(property "Reference" "D207"
			(at -7.822038 0.7365 0)
			(layer "F.SilkS")
			(effects
				(font
					(size 0.7 0.7)
					(thickness 0.15)
				)
				(justify right bottom)
			)
		)
		(property "Value" "LED_G_0603_KP-1608CGCK"
			(at -0.001 1.599 0)
			(layer "F.Fab")
			(effects
				(font
					(size 0.7 0.7)
					(thickness 0.15)
				)
				(justify right bottom)
			)
		)
		(property "Datasheet" "http://www.kingbright.com/attachments/file/psearch//000/00/00/KP-1608CGCK(Ver.23B).pdf"
			(at 0 0 180)
			(layer "F.Fab")
			(hide yes)
			(effects
				(font
					(size 1.27 1.27)
					(thickness 0.15)
				)
			)
		)
		(property "MPN" "KP-1608CGCK"
			(at 0 0 180)
			(unlocked yes)
			(layer "F.Fab")
			(hide yes)
			(effects
				(font
					(size 1 1)
					(thickness 0.15)
				)
			)
		)
		(property "Manufacturer" "Kingbright"
			(at 0 0 180)
			(unlocked yes)
			(layer "F.Fab")
			(hide yes)
			(effects
				(font
					(size 1 1)
					(thickness 0.15)
				)
			)
		)
		(property "Color" "Green"
			(at 0 0 180)
			(unlocked yes)
			(layer "F.Fab")
			(hide yes)
			(effects
				(font
					(size 1 1)
					(thickness 0.15)
				)
			)
		)
		(property "Author" "Antmicro"
			(at 0 0 180)
			(unlocked yes)
			(layer "F.Fab")
			(hide yes)
			(effects
				(font
					(size 1 1)
					(thickness 0.15)
				)
			)
		)
		(property "License" "Apache-2.0"
			(at 0 0 180)
			(unlocked yes)
			(layer "F.Fab")
			(hide yes)
			(effects
				(font
					(size 1 1)
					(thickness 0.15)
				)
			)
		)
		(sheetname "/Compute module/")
		(sheetfile "compute-module.kicad_sch")
		(attr smd exclude_from_bom dnp)
		(fp_line
			(start 0.22 0.35)
			(end -0.22 0.35)
			(stroke
				(width 0.15)
				(type solid)
			)
			(layer "F.SilkS")
		)
		(fp_line
			(start 0.22 -0.35)
			(end -0.22 -0.35)
			(stroke
				(width 0.15)
				(type solid)
			)
			(layer "F.SilkS")
		)
		(fp_line
			(start 0.105328 0.201008)
			(end 0.105328 -0.198992)
			(stroke
				(width 0.1)
				(type solid)
			)
			(layer "F.SilkS")
		)
		(fp_line
			(start 0.105328 0.201008)
			(end -0.094672 0.001008)
			(stroke
				(width 0.1)
				(type solid)
			)
			(layer "F.SilkS")
		)
		(fp_line
			(start 0.105328 0.001008)
			(end 0.24 0.001)
			(stroke
				(width 0.1)
				(type solid)
			)
			(layer "F.SilkS")
		)
		(fp_line
			(start -0.094672 0.201008)
			(end -0.094672 -0.198992)
			(stroke
				(width 0.1)
				(type solid)
			)
			(layer "F.SilkS")
		)
		(fp_line
			(start -0.094672 0.001008)
			(end 0.105328 -0.198992)
			(stroke
				(width 0.1)
				(type solid)
			)
			(layer "F.SilkS")
		)
		(fp_line
			(start -0.094672 0.001008)
			(end -0.24 0.001008)
			(stroke
				(width 0.1)
				(type solid)
			)
			(layer "F.SilkS")
		)
		(fp_line
			(start -1.18 -0.319)
			(end -1.18 0.321)
			(stroke
				(width 0.15)
				(type solid)
			)
			(layer "F.SilkS")
		)
		(fp_rect
			(start 1.25 0.65)
			(end -1.25 -0.65)
			(stroke
				(width 0.05)
				(type solid)
			)
			(fill no)
			(layer "F.CrtYd")
		)
		(fp_line
			(start 0.599 0)
			(end 0.201 0)
			(stroke
				(width 0.15)
				(type solid)
			)
			(layer "F.Fab")
		)
		(fp_line
			(start 0.201 0.2)
			(end 0.201 0)
			(stroke
				(width 0.15)
				(type solid)
			)
			(layer "F.Fab")
		)
		(fp_line
			(start 0.201 0)
			(end 0.201 -0.202)
			(stroke
				(width 0.15)
				(type solid)
			)
			(layer "F.Fab")
		)
		(fp_line
			(start 0.201 -0.202)
			(end -0.101 0)
			(stroke
				(width 0.15)
				(type solid)
			)
			(layer "F.Fab")
		)
		(fp_line
			(start -0.101 0)
			(end 0.201 0.2)
			(stroke
				(width 0.15)
				(type solid)
			)
			(layer "F.Fab")
		)
		(fp_line
			(start -0.199 0.2)
			(end -0.199 0.1)
			(stroke
				(width 0.15)
				(type solid)
			)
			(layer "F.Fab")
		)
		(fp_line
			(start -0.199 0)
			(end -0.597 0)
			(stroke
				(width 0.15)
				(type solid)
			)
			(layer "F.Fab")
		)
		(fp_line
			(start -0.199 -0.202)
			(end -0.199 0.1)
			(stroke
				(width 0.15)
				(type solid)
			)
			(layer "F.Fab")
		)
		(fp_rect
			(start 0.848 0.4)
			(end -0.85 -0.402)
			(stroke
				(width 0.15)
				(type solid)
			)
			(fill no)
			(layer "F.Fab")
		)
		(fp_text user "${REFERENCE}"
			(at -1.4224 5.999 180)
			(layer "F.Fab")
			(effects
				(font
					(size 0.7 0.7)
					(thickness 0.15)
				)
				(justify left bottom)
			)
		)
		(fp_text user "Author: Antmicro"
			(at -1.4224 4.799 180)
			(layer "F.Fab")
			(effects
				(font
					(size 0.7 0.7)
					(thickness 0.15)
				)
				(justify left bottom)
			)
		)
		(fp_text user "License: Apache-2.0"
			(at -1.4224 3.599 180)
			(layer "F.Fab")
			(effects
				(font
					(size 0.7 0.7)
					(thickness 0.15)
				)
				(justify left bottom)
			)
		)
		(pad "1" smd roundrect
			(at -0.7 0)
			(size 0.8 1)
			(layers "F.Cu" "F.Mask" "F.Paste")
			(roundrect_rratio 0.2)
			(net 469 "Net-(D207-C)")
			(pinfunction "C")
			(pintype "passive")
		)
		(pad "2" smd roundrect
			(at 0.7 0)
			(size 0.8 1)
			(layers "F.Cu" "F.Mask" "F.Paste")
			(roundrect_rratio 0.2)
			(net 9 "+3V3")
			(pinfunction "A")
			(pintype "passive")
		)
	)
	(footprint "antmicro-footprints:R_0402_1005Metric"
		(layer "F.Cu")
		(at 108.1 156.7915 180)
		(descr "Resistor SMD 0402")
		(tags "resistor SMD 0402")
		(property "Reference" "R226"
			(at 1.91 -2.495 180)
			(layer "F.SilkS")
			(effects
				(font
					(size 0.7 0.7)
					(thickness 0.15)
				)
				(justify left bottom)
			)
		)
		(property "Value" "R_0R_0402"
			(at -1.011843 1.772047 180)
			(layer "F.Fab")
			(effects
				(font
					(size 0.7 0.7)
					(thickness 0.15)
				)
				(justify left bottom)
			)
		)
		(property "Datasheet" "https://industrial.panasonic.com/cdbs/www-data/pdf/RDA0000/AOA0000C301.pdf"
			(at 0 0 180)
			(layer "F.Fab")
			(hide yes)
			(effects
				(font
					(size 1.27 1.27)
					(thickness 0.15)
				)
			)
		)
		(property "Manufacturer" "Panasonic"
			(at 0 0 180)
			(unlocked yes)
			(layer "F.Fab")
			(hide yes)
			(effects
				(font
					(size 1 1)
					(thickness 0.15)
				)
			)
		)
		(property "MPN" "ERJ2GE0R00X"
			(at 0 0 180)
			(unlocked yes)
			(layer "F.Fab")
			(hide yes)
			(effects
				(font
					(size 1 1)
					(thickness 0.15)
				)
			)
		)
		(property "Val" "0R"
			(at 0 0 180)
			(unlocked yes)
			(layer "F.Fab")
			(hide yes)
			(effects
				(font
					(size 1 1)
					(thickness 0.15)
				)
			)
		)
		(property "License" "Apache-2.0"
			(at 0 0 180)
			(unlocked yes)
			(layer "F.Fab")
			(hide yes)
			(effects
				(font
					(size 1 1)
					(thickness 0.15)
				)
			)
		)
		(property "Author" "Antmicro"
			(at 0 0 180)
			(unlocked yes)
			(layer "F.Fab")
			(hide yes)
			(effects
				(font
					(size 1 1)
					(thickness 0.15)
				)
			)
		)
		(property "Tolerance" "~"
			(at 0 0 180)
			(unlocked yes)
			(layer "F.Fab")
			(hide yes)
			(effects
				(font
					(size 1 1)
					(thickness 0.15)
				)
			)
		)
		(property "Current" "1A"
			(at 0 0 180)
			(unlocked yes)
			(layer "F.Fab")
			(hide yes)
			(effects
				(font
					(size 1 1)
					(thickness 0.15)
				)
			)
		)
		(sheetname "/Compute module/")
		(sheetfile "compute-module.kicad_sch")
		(attr smd)
		(fp_rect
			(start -0.925 -0.47)
			(end 0.925 0.47)
			(stroke
				(width 0.05)
				(type default)
			)
			(fill no)
			(layer "F.CrtYd")
		)
		(fp_rect
			(start -0.5 -0.25)
			(end 0.5 0.25)
			(stroke
				(width 0.15)
				(type solid)
			)
			(fill no)
			(layer "F.Fab")
		)
		(fp_text user "${REFERENCE}"
			(at -0.95 3.168 180)
			(layer "F.Fab")
			(effects
				(font
					(size 0.7 0.7)
					(thickness 0.15)
				)
				(justify left bottom)
			)
		)
		(fp_text user "License: Apache-2.0"
			(at -0.95 5.169 180)
			(layer "F.Fab")
			(effects
				(font
					(size 0.7 0.7)
					(thickness 0.15)
				)
				(justify left bottom)
			)
		)
		(fp_text user "Author: Antmicro"
			(at -0.95 4.169 180)
			(layer "F.Fab")
			(effects
				(font
					(size 0.7 0.7)
					(thickness 0.15)
				)
				(justify left bottom)
			)
		)
		(pad "1" smd roundrect
			(at -0.48 0 180)
			(size 0.59 0.64)
			(layers "F.Cu" "F.Mask" "F.Paste")
			(roundrect_rratio 0.25)
			(net 151 "/Compute module/R2_P")
			(pintype "passive")
		)
		(pad "2" smd roundrect
			(at 0.48 0 180)
			(size 0.59 0.64)
			(layers "F.Cu" "F.Mask" "F.Paste")
			(roundrect_rratio 0.25)
			(net 163 "/Compute module/NVMe.RX2_P")
			(pintype "passive")
		)
	)
)
